FILE_TYPE = MULTI_PHYS_TABLE;

PART 'TP_PIONT'
CLASS = IO 

{========================================================================================}
:'JEDEC_TYPE'           = 'JEDEC_TYPE'         ;
{========================================================================================}
 'TP_60C_BOT'          = 'TP_60C_BOT' 
 'TP_80C_BOT'          = 'TP_80C_BOT'        
 'TP010C020_PTH'       = 'TP010C020_PTH'  
 'TP008CT018B030_PTH'       = 'TP008CT018B030_PTH'  
 'TP010CT020B030_PTH'       = 'TP010CT020B030_PTH'
 'TP020CT030B040_PTH'       = 'TP020CT030B040_PTH'
 'TP010CT018B018_PTH'       = 'TP010CT018B018_PTH'
 'TP036CT055B055_PTH'       = 'TP036CT055B055_PTH'
 'TP036ST055B055_PTH'       = 'TP036ST055B055_PTH'
 'TP-30-TOP'                = 'TP-30-TOP'
 'TP008CT022B018_PTH'       = 'TP008CT022B018_PTH'
 'TP020CT034B034_PTH'       = 'TP020CT034B034_PTH'
 'TP008CT018B018_PTH'       = 'TP008CT018B018_PTH'

END_PART

END.

